(kicad_pcb
	(version 20260206)
	(generator "pcbnew")
	(generator_version "10.0")
	(general
		(thickness 1.6)
		(legacy_teardrops no)
	)
	(paper "A4")
	(title_block
		(title "04192023_DAF0TMB3IC0_F0TG_MB_C_brd_V02_OCP.brd")
		(comment 1 "Grand Teton / footprints 4247-4247 of 8354")
	)
	(layers
		(0 "F.Cu" signal "TOP")
		(4 "In1.Cu" signal "GND")
		(6 "In2.Cu" signal "IN1")
		(8 "In3.Cu" signal "GND1")
		(10 "In4.Cu" signal "IN2")
		(12 "In5.Cu" signal "GND2")
		(14 "In6.Cu" signal "IN3")
		(16 "In7.Cu" signal "GND3")
		(18 "In8.Cu" signal "VCC")
		(20 "In9.Cu" signal "VCC1")
		(22 "In10.Cu" signal "GND4")
		(24 "In11.Cu" signal "IN4")
		(26 "In12.Cu" signal "GND5")
		(28 "In13.Cu" signal "IN5")
		(30 "In14.Cu" signal "GND6")
		(32 "In15.Cu" signal "IN6")
		(34 "In16.Cu" signal "GND7")
		(2 "B.Cu" signal "BOTTOM")
		(9 "F.Adhes" user "F.Adhesive")
		(11 "B.Adhes" user "B.Adhesive")
		(13 "F.Paste" user "Package Geometry/Pastemask Top")
		(15 "B.Paste" user "Package Geometry/Pastemask Bottom")
		(5 "F.SilkS" user "Ref Des/Silkscreen Top")
		(7 "B.SilkS" user "Ref Des/Silkscreen Bottom")
		(1 "F.Mask" user "Board Geometry/Soldermask Top")
		(3 "B.Mask" user "Board Geometry/Soldermask Bottom")
		(17 "Dwgs.User" user "User.Drawings")
		(19 "Cmts.User" user "User.Comments")
		(21 "Eco1.User" user "User.Eco1")
		(23 "Eco2.User" user "User.Eco2")
		(25 "Edge.Cuts" user "Board Geometry/Outline")
		(27 "Margin" user)
		(31 "F.CrtYd" user "Package Geometry/Place Bound Top")
		(29 "B.CrtYd" user "Package Geometry/Place Bound Bottom")
		(35 "F.Fab" user "Ref Des/Assembly Top")
		(33 "B.Fab" user "Ref Des/Assembly Bottom")
	)
	(footprint ""
		(layer "F.Cu")
		(at 258.275836 -75.770994)
		(property "Reference" "R3772"
			(at 0 0 0)
			(layer "F.SilkS")
			(hide yes)
			(effects
				(font
					(size 1.27 1.27)
				)
			)
		)
		(property "Value" ""
			(at 0 0 0)
			(layer "F.Fab")
			(effects
				(font
					(size 1.27 1.27)
				)
			)
		)
		(duplicate_pad_numbers_are_jumpers no)
		(fp_line
			(start -0.7874 -0.4064)
			(end 0.7874 -0.4064)
			(stroke
				(width 0.1524)
				(type default)
			)
			(layer "F.SilkS")
		)
		(fp_line
			(start -0.7874 0.4064)
			(end -0.7874 -0.4064)
			(stroke
				(width 0.1524)
				(type default)
			)
			(layer "F.SilkS")
		)
		(fp_line
			(start 0.7874 -0.4064)
			(end 0.7874 0.4064)
			(stroke
				(width 0.1524)
				(type default)
			)
			(layer "F.SilkS")
		)
		(fp_line
			(start 0.7874 0.4064)
			(end -0.7874 0.4064)
			(stroke
				(width 0.1524)
				(type default)
			)
			(layer "F.SilkS")
		)
		(fp_line
			(start -0.67945 -0.305054)
			(end -0.12065 -0.305054)
			(stroke
				(width 0.1)
				(type default)
			)
			(layer "F.Fab")
		)
		(fp_line
			(start -0.67945 0.3048)
			(end -0.67945 -0.305054)
			(stroke
				(width 0.1)
				(type default)
			)
			(layer "F.Fab")
		)
		(fp_line
			(start -0.12065 -0.305054)
			(end -0.12065 -0.2794)
			(stroke
				(width 0.1)
				(type default)
			)
			(layer "F.Fab")
		)
		(fp_line
			(start -0.12065 -0.2794)
			(end 0.12065 -0.2794)
			(stroke
				(width 0.1)
				(type default)
			)
			(layer "F.Fab")
		)
		(fp_line
			(start -0.12065 0.2794)
			(end -0.12065 0.3048)
			(stroke
				(width 0.1)
				(type default)
			)
			(layer "F.Fab")
		)
		(fp_line
			(start -0.12065 0.3048)
			(end -0.67945 0.3048)
			(stroke
				(width 0.1)
				(type default)
			)
			(layer "F.Fab")
		)
		(fp_line
			(start 0.120396 0.2794)
			(end -0.12065 0.2794)
			(stroke
				(width 0.1)
				(type default)
			)
			(layer "F.Fab")
		)
		(fp_line
			(start 0.120396 0.3048)
			(end 0.120396 0.2794)
			(stroke
				(width 0.1)
				(type default)
			)
			(layer "F.Fab")
		)
		(fp_line
			(start 0.12065 -0.3048)
			(end 0.67945 -0.3048)
			(stroke
				(width 0.1)
				(type default)
			)
			(layer "F.Fab")
		)
		(fp_line
			(start 0.12065 -0.2794)
			(end 0.12065 -0.3048)
			(stroke
				(width 0.1)
				(type default)
			)
			(layer "F.Fab")
		)
		(fp_line
			(start 0.67945 -0.3048)
			(end 0.67945 0.3048)
			(stroke
				(width 0.1)
				(type default)
			)
			(layer "F.Fab")
		)
		(fp_line
			(start 0.67945 0.3048)
			(end 0.120396 0.3048)
			(stroke
				(width 0.1)
				(type default)
			)
			(layer "F.Fab")
		)
		(pad "1" smd circle
			(at -0.40005 0)
			(size 0 0)
			(layers "F.Cu" "F.Mask" "F.Paste")
			(net "RST_SMB_BUF_E1S_0_N")
		)
		(pad "2" smd circle
			(at 0.40005 0)
			(size 0 0)
			(layers "F.Cu" "F.Mask" "F.Paste")
			(net "RST_SMB_E1S_0_N")
		)
	)
)
